(kicad_pcb
	(version 20260206)
	(generator "pcbnew")
	(generator_version "10.0")
	(general
		(thickness 1.6)
		(legacy_teardrops no)
	)
	(paper "A4")
	(title_block
		(title "Wiwynn_Tioga_Pass_MB.brd")
		(comment 1 "Tioga Pass / footprint 190 of 4770 (U2D1), pads 807-911 of 3647")
	)
	(layers
		(0 "F.Cu" signal "TOP")
		(4 "In1.Cu" signal "L2GND")
		(6 "In2.Cu" signal "L3")
		(8 "In3.Cu" signal "L4GND")
		(10 "In4.Cu" signal "L5")
		(12 "In5.Cu" signal "L6GND")
		(14 "In6.Cu" signal "L7VCC")
		(16 "In7.Cu" signal "L8VCC")
		(18 "In8.Cu" signal "L9GND")
		(20 "In9.Cu" signal "L10")
		(22 "In10.Cu" signal "L11GND")
		(24 "In11.Cu" signal "L12")
		(26 "In12.Cu" signal "L13GND")
		(2 "B.Cu" signal "BOTTOM")
		(9 "F.Adhes" user "F.Adhesive")
		(11 "B.Adhes" user "B.Adhesive")
		(13 "F.Paste" user "Package Geometry/Pastemask Top")
		(15 "B.Paste" user "Package Geometry/Pastemask Bottom")
		(5 "F.SilkS" user "Ref Des/Silkscreen Top")
		(7 "B.SilkS" user "Ref Des/Silkscreen Bottom")
		(1 "F.Mask" user "Board Geometry/Soldermask Top")
		(3 "B.Mask" user "Board Geometry/Soldermask Bottom")
		(17 "Dwgs.User" user "User.Drawings")
		(19 "Cmts.User" user "User.Comments")
		(21 "Eco1.User" user "User.Eco1")
		(23 "Eco2.User" user "User.Eco2")
		(25 "Edge.Cuts" user "Board Geometry/Outline")
		(27 "Margin" user)
		(31 "F.CrtYd" user "Package Geometry/Place Bound Top")
		(29 "B.CrtYd" user "Package Geometry/Place Bound Bottom")
		(35 "F.Fab" user "Ref Des/Assembly Top")
		(33 "B.Fab" user "Ref Des/Assembly Bottom")
	)
	(footprint ""
		(layer "F.Cu")
		(at 104.99979 -76.550012 180)
		(property "Reference" "U2D1"
			(at 25.19299 30.484318 0)
			(unlocked yes)
			(layer "F.SilkS")
			(effects
				(font
					(size 0.7874 0.5842)
					(thickness 0.1524)
				)
			)
		)
		(property "Value" ""
			(at 0 0 180)
			(layer "F.Fab")
			(effects
				(font
					(size 1.27 1.27)
				)
			)
		)
		(duplicate_pad_numbers_are_jumpers no)
		(pad "BB79" smd circle
			(at 31.240984 -6.596126)
			(size 0.4318 0.4318)
			(layers "F.Cu" "F.Mask" "F.Paste")
			(net "GND")
		)
		(pad "BB81" smd circle
			(at 32.958024 -6.596126)
			(size 0.4318 0.4318)
			(layers "F.Cu" "F.Mask" "F.Paste")
			(net "GND")
		)
		(pad "BB83" smd circle
			(at 34.675064 -6.596126)
			(size 0.4318 0.4318)
			(layers "F.Cu" "F.Mask" "F.Paste")
			(net "GND")
		)
		(pad "BB85" smd custom
			(at 36.392104 -6.596126 270)
			(size 0.10795 0.10795)
			(layers "F.Cu" "F.Mask" "F.Paste")
			(net "PVCCIN_CPU1")
			(options
				(clearance outline)
				(anchor circle)
			)
			(primitives
				(gr_poly
					(pts
						(arc
							(start 0.2159 -0.0381)
							(mid 0 -0.254)
							(end -0.2159 -0.0381)
						)
						(arc
							(start -0.2159 0.0381)
							(mid 0 0.254)
							(end 0.2159 0.0381)
						)
					)
					(width 0)
					(fill yes)
				)
			)
		)
		(pad "BC2" smd custom
			(at -36.392104 -4.300474 90)
			(size 0.10795 0.10795)
			(layers "F.Cu" "F.Mask" "F.Paste")
			(net "UPI_CPU1_CPU0_P0P0_DP<17>")
			(options
				(clearance outline)
				(anchor circle)
			)
			(primitives
				(gr_poly
					(pts
						(arc
							(start 0.2159 -0.0381)
							(mid 0 -0.254)
							(end -0.2159 -0.0381)
						)
						(arc
							(start -0.2159 0.0381)
							(mid 0 0.254)
							(end 0.2159 0.0381)
						)
					)
					(width 0)
					(fill yes)
				)
			)
		)
		(pad "BC4" smd circle
			(at -34.675064 -4.300474)
			(size 0.4318 0.4318)
			(layers "F.Cu" "F.Mask" "F.Paste")
			(net "GND")
		)
		(pad "BC6" smd circle
			(at -32.958024 -4.300474)
			(size 0.4318 0.4318)
			(layers "F.Cu" "F.Mask" "F.Paste")
			(net "UPI_CPU0_CPU1_P0P0_DP<14>")
		)
		(pad "BC8" smd circle
			(at -31.240984 -4.300474)
			(size 0.4318 0.4318)
			(layers "F.Cu" "F.Mask" "F.Paste")
			(net "GND")
		)
		(pad "BC10" smd circle
			(at -29.523944 -4.300474)
			(size 0.4318 0.4318)
			(layers "F.Cu" "F.Mask" "F.Paste")
			(net "UPI_CPU0_CPU1_P0P0_DN<18>")
		)
		(pad "BC12" smd circle
			(at -27.806904 -4.300474)
			(size 0.4318 0.4318)
			(layers "F.Cu" "F.Mask" "F.Paste")
			(net "GND")
		)
		(pad "BC14" smd circle
			(at -26.090118 -4.300474)
			(size 0.4318 0.4318)
			(layers "F.Cu" "F.Mask" "F.Paste")
			(net "TP_CPU1_RSVD_162")
		)
		(pad "BC16" smd circle
			(at -24.373078 -4.300474)
			(size 0.4318 0.4318)
			(layers "F.Cu" "F.Mask" "F.Paste")
			(net "GND")
		)
		(pad "BC18" smd circle
			(at -22.656038 -4.300474)
			(size 0.4318 0.4318)
			(layers "F.Cu" "F.Mask" "F.Paste")
			(net "TP_CPU1_RSVD_161")
		)
		(pad "BC20" smd circle
			(at -20.938998 -4.300474)
			(size 0.4318 0.4318)
			(layers "F.Cu" "F.Mask" "F.Paste")
			(net "TP_CPU1_RSVD_160")
		)
		(pad "BC22" smd circle
			(at -19.221958 -4.300474)
			(size 0.4318 0.4318)
			(layers "F.Cu" "F.Mask" "F.Paste")
			(net "TP_CPU1_RSVD_159")
		)
		(pad "BC24" smd circle
			(at -17.504918 -4.300474)
			(size 0.4318 0.4318)
			(layers "F.Cu" "F.Mask" "F.Paste")
			(net "PWRGD_CPU1_G")
		)
		(pad "BC26" smd circle
			(at -15.787878 -4.300474)
			(size 0.4318 0.4318)
			(layers "F.Cu" "F.Mask" "F.Paste")
			(net "PVCCIO_CPU1")
		)
		(pad "BC60" smd circle
			(at 14.929612 -6.100572)
			(size 0.508 0.508)
			(layers "F.Cu" "F.Mask" "F.Paste")
			(net "PVCCIN_CPU1")
		)
		(pad "BC62" smd circle
			(at 16.646398 -6.100572)
			(size 0.4318 0.4318)
			(layers "F.Cu" "F.Mask" "F.Paste")
			(net "PVCCIN_CPU1")
		)
		(pad "BC64" smd circle
			(at 18.363438 -6.100572)
			(size 0.4318 0.4318)
			(layers "F.Cu" "F.Mask" "F.Paste")
			(net "TP_CPU1_RSVD_158")
		)
		(pad "BC66" smd circle
			(at 20.080478 -6.100572)
			(size 0.4318 0.4318)
			(layers "F.Cu" "F.Mask" "F.Paste")
			(net "TP_CPU1_RSVD_157")
		)
		(pad "BC68" smd circle
			(at 21.797518 -6.100572)
			(size 0.4318 0.4318)
			(layers "F.Cu" "F.Mask" "F.Paste")
			(net "TP_CPU1_RSVD_156")
		)
		(pad "BC70" smd circle
			(at 23.514558 -6.100572)
			(size 0.4318 0.4318)
			(layers "F.Cu" "F.Mask" "F.Paste")
			(net "GND")
		)
		(pad "BC72" smd circle
			(at 25.231598 -6.100572)
			(size 0.4318 0.4318)
			(layers "F.Cu" "F.Mask" "F.Paste")
			(net "GND")
		)
		(pad "BC74" smd circle
			(at 26.948384 -6.100572)
			(size 0.4318 0.4318)
			(layers "F.Cu" "F.Mask" "F.Paste")
			(net "GND")
		)
		(pad "BC76" smd circle
			(at 28.665424 -6.100572)
			(size 0.4318 0.4318)
			(layers "F.Cu" "F.Mask" "F.Paste")
			(net "GND")
		)
		(pad "BC78" smd circle
			(at 30.382464 -6.100572)
			(size 0.4318 0.4318)
			(layers "F.Cu" "F.Mask" "F.Paste")
			(net "GND")
		)
		(pad "BC80" smd circle
			(at 32.099504 -6.100572)
			(size 0.4318 0.4318)
			(layers "F.Cu" "F.Mask" "F.Paste")
			(net "GND")
		)
		(pad "BC82" smd circle
			(at 33.816544 -6.100572)
			(size 0.4318 0.4318)
			(layers "F.Cu" "F.Mask" "F.Paste")
			(net "GND")
		)
		(pad "BC84" smd circle
			(at 35.533584 -6.100572)
			(size 0.4318 0.4318)
			(layers "F.Cu" "F.Mask" "F.Paste")
			(net "PVCCIN_CPU1")
		)
		(pad "BD3" smd custom
			(at -35.533584 -3.805428 90)
			(size 0.10795 0.10795)
			(layers "F.Cu" "F.Mask" "F.Paste")
			(net "UPI_CPU1_CPU0_P0P0_DP<18>")
			(options
				(clearance outline)
				(anchor circle)
			)
			(primitives
				(gr_poly
					(pts
						(arc
							(start 0.2159 -0.0381)
							(mid 0 -0.254)
							(end -0.2159 -0.0381)
						)
						(arc
							(start -0.2159 0.0381)
							(mid 0 0.254)
							(end 0.2159 0.0381)
						)
					)
					(width 0)
					(fill yes)
				)
			)
		)
		(pad "BD5" smd circle
			(at -33.816544 -3.805428)
			(size 0.4318 0.4318)
			(layers "F.Cu" "F.Mask" "F.Paste")
			(net "GND")
		)
		(pad "BD7" smd circle
			(at -32.099504 -3.805428)
			(size 0.4318 0.4318)
			(layers "F.Cu" "F.Mask" "F.Paste")
			(net "UPI_CPU0_CPU1_P0P0_DN<15>")
		)
		(pad "BD9" smd circle
			(at -30.382464 -3.805428)
			(size 0.4318 0.4318)
			(layers "F.Cu" "F.Mask" "F.Paste")
			(net "UPI_CPU0_CPU1_P0P0_DP<18>")
		)
		(pad "BD11" smd circle
			(at -28.665424 -3.805428)
			(size 0.4318 0.4318)
			(layers "F.Cu" "F.Mask" "F.Paste")
			(net "GND")
		)
		(pad "BD13" smd circle
			(at -26.948384 -3.805428)
			(size 0.4318 0.4318)
			(layers "F.Cu" "F.Mask" "F.Paste")
			(net "PVCCMCP_CPU1")
		)
		(pad "BD15" smd circle
			(at -25.231598 -3.805428)
			(size 0.4318 0.4318)
			(layers "F.Cu" "F.Mask" "F.Paste")
			(net "GND")
		)
		(pad "BD17" smd circle
			(at -23.514558 -3.805428)
			(size 0.4318 0.4318)
			(layers "F.Cu" "F.Mask" "F.Paste")
			(net "TP_CPU1_RSVD_155")
		)
		(pad "BD19" smd circle
			(at -21.797518 -3.805428)
			(size 0.4318 0.4318)
			(layers "F.Cu" "F.Mask" "F.Paste")
			(net "TP_CPU1_RSVD_154")
		)
		(pad "BD21" smd circle
			(at -20.080478 -3.805428)
			(size 0.4318 0.4318)
			(layers "F.Cu" "F.Mask" "F.Paste")
			(net "GND")
		)
		(pad "BD23" smd circle
			(at -18.363438 -3.805428)
			(size 0.4318 0.4318)
			(layers "F.Cu" "F.Mask" "F.Paste")
			(net "H_CPU1_BMCINIT")
		)
		(pad "BD25" smd circle
			(at -16.646398 -3.805428)
			(size 0.4318 0.4318)
			(layers "F.Cu" "F.Mask" "F.Paste")
			(net "CLK_100M_CPU1_RC_REFCLK1_DP")
		)
		(pad "BD27" smd circle
			(at -14.929612 -3.805428)
			(size 0.4318 0.4318)
			(layers "F.Cu" "F.Mask" "F.Paste")
			(net "GND")
		)
		(pad "BD61" smd circle
			(at 15.787878 -5.605272)
			(size 0.4318 0.4318)
			(layers "F.Cu" "F.Mask" "F.Paste")
			(net "PVCCIN_CPU1")
		)
		(pad "BD63" smd circle
			(at 17.504918 -5.605272)
			(size 0.4318 0.4318)
			(layers "F.Cu" "F.Mask" "F.Paste")
			(net "GND")
		)
		(pad "BD65" smd circle
			(at 19.221958 -5.605272)
			(size 0.4318 0.4318)
			(layers "F.Cu" "F.Mask" "F.Paste")
			(net "TP_CPU1_RSVD_152")
		)
		(pad "BD67" smd circle
			(at 20.938998 -5.605272)
			(size 0.4318 0.4318)
			(layers "F.Cu" "F.Mask" "F.Paste")
			(net "TP_CPU1_RSVD_151")
		)
		(pad "BD69" smd circle
			(at 22.656038 -5.605272)
			(size 0.4318 0.4318)
			(layers "F.Cu" "F.Mask" "F.Paste")
			(net "TP_CPU1_RSVD_150")
		)
		(pad "BD71" smd circle
			(at 24.373078 -5.605272)
			(size 0.4318 0.4318)
			(layers "F.Cu" "F.Mask" "F.Paste")
			(net "GND")
		)
		(pad "BD73" smd circle
			(at 26.090118 -5.605272)
			(size 0.4318 0.4318)
			(layers "F.Cu" "F.Mask" "F.Paste")
			(net "PVCCIN_CPU1")
		)
		(pad "BD75" smd circle
			(at 27.806904 -5.605272)
			(size 0.4318 0.4318)
			(layers "F.Cu" "F.Mask" "F.Paste")
			(net "PVCCIN_CPU1")
		)
		(pad "BD77" smd circle
			(at 29.523944 -5.605272)
			(size 0.4318 0.4318)
			(layers "F.Cu" "F.Mask" "F.Paste")
			(net "PVCCIN_CPU1")
		)
		(pad "BD79" smd circle
			(at 31.240984 -5.605272)
			(size 0.4318 0.4318)
			(layers "F.Cu" "F.Mask" "F.Paste")
			(net "PVCCIN_CPU1")
		)
		(pad "BD81" smd circle
			(at 32.958024 -5.605272)
			(size 0.4318 0.4318)
			(layers "F.Cu" "F.Mask" "F.Paste")
			(net "PVCCIN_CPU1")
		)
		(pad "BD83" smd circle
			(at 34.675064 -5.605272)
			(size 0.4318 0.4318)
			(layers "F.Cu" "F.Mask" "F.Paste")
			(net "PVCCIN_CPU1")
		)
		(pad "BD85" smd custom
			(at 36.392104 -5.605272 270)
			(size 0.10795 0.10795)
			(layers "F.Cu" "F.Mask" "F.Paste")
			(net "PVCCIN_CPU1")
			(options
				(clearance outline)
				(anchor circle)
			)
			(primitives
				(gr_poly
					(pts
						(arc
							(start 0.2159 -0.0381)
							(mid 0 -0.254)
							(end -0.2159 -0.0381)
						)
						(arc
							(start -0.2159 0.0381)
							(mid 0 0.254)
							(end 0.2159 0.0381)
						)
					)
					(width 0)
					(fill yes)
				)
			)
		)
		(pad "BE4" smd circle
			(at -34.675064 -3.309874)
			(size 0.4318 0.4318)
			(layers "F.Cu" "F.Mask" "F.Paste")
			(net "GND")
		)
		(pad "BE6" smd circle
			(at -32.958024 -3.309874)
			(size 0.4318 0.4318)
			(layers "F.Cu" "F.Mask" "F.Paste")
			(net "GND")
		)
		(pad "BE8" smd circle
			(at -31.240984 -3.309874)
			(size 0.4318 0.4318)
			(layers "F.Cu" "F.Mask" "F.Paste")
			(net "GND")
		)
		(pad "BE10" smd circle
			(at -29.523944 -3.309874)
			(size 0.4318 0.4318)
			(layers "F.Cu" "F.Mask" "F.Paste")
			(net "GND")
		)
		(pad "BE12" smd circle
			(at -27.806904 -3.309874)
			(size 0.4318 0.4318)
			(layers "F.Cu" "F.Mask" "F.Paste")
			(net "PVCCMCP_CPU1")
		)
		(pad "BE14" smd circle
			(at -26.090118 -3.309874)
			(size 0.4318 0.4318)
			(layers "F.Cu" "F.Mask" "F.Paste")
			(net "PVCCMCP_CPU1")
		)
		(pad "BE16" smd circle
			(at -24.373078 -3.309874)
			(size 0.4318 0.4318)
			(layers "F.Cu" "F.Mask" "F.Paste")
			(net "CLK_156M_OSC_CPU1_HFI_DN")
		)
		(pad "BE18" smd circle
			(at -22.656038 -3.309874)
			(size 0.4318 0.4318)
			(layers "F.Cu" "F.Mask" "F.Paste")
			(net "TP_CPU1_RSVD_149")
		)
		(pad "BE20" smd circle
			(at -20.938998 -3.309874)
			(size 0.4318 0.4318)
			(layers "F.Cu" "F.Mask" "F.Paste")
			(net "TP_CPU1_RSVD_148")
		)
		(pad "BE22" smd circle
			(at -19.221958 -3.309874)
			(size 0.4318 0.4318)
			(layers "F.Cu" "F.Mask" "F.Paste")
			(net "TP_CPU1_RSVD_147")
		)
		(pad "BE24" smd circle
			(at -17.504918 -3.309874)
			(size 0.4318 0.4318)
			(layers "F.Cu" "F.Mask" "F.Paste")
			(net "PVCCIO_CPU1")
		)
		(pad "BE26" smd circle
			(at -15.787878 -3.309874)
			(size 0.4318 0.4318)
			(layers "F.Cu" "F.Mask" "F.Paste")
			(net "GND")
		)
		(pad "BE60" smd circle
			(at 14.929612 -5.109972)
			(size 0.508 0.508)
			(layers "F.Cu" "F.Mask" "F.Paste")
			(net "PVCCIN_CPU1")
		)
		(pad "BE62" smd circle
			(at 16.646398 -5.109972)
			(size 0.4318 0.4318)
			(layers "F.Cu" "F.Mask" "F.Paste")
			(net "PVCCIN_CPU1")
		)
		(pad "BE64" smd circle
			(at 18.363438 -5.109972)
			(size 0.4318 0.4318)
			(layers "F.Cu" "F.Mask" "F.Paste")
			(net "GND")
		)
		(pad "BE66" smd circle
			(at 20.080478 -5.109972)
			(size 0.4318 0.4318)
			(layers "F.Cu" "F.Mask" "F.Paste")
			(net "GND")
		)
		(pad "BE68" smd circle
			(at 21.797518 -5.109972)
			(size 0.4318 0.4318)
			(layers "F.Cu" "F.Mask" "F.Paste")
			(net "GND")
		)
		(pad "BE70" smd circle
			(at 23.514558 -5.109972)
			(size 0.4318 0.4318)
			(layers "F.Cu" "F.Mask" "F.Paste")
			(net "GND")
		)
		(pad "BE72" smd circle
			(at 25.231598 -5.109972)
			(size 0.4318 0.4318)
			(layers "F.Cu" "F.Mask" "F.Paste")
			(net "PVCCIN_CPU1")
		)
		(pad "BE74" smd circle
			(at 26.948384 -5.109972)
			(size 0.4318 0.4318)
			(layers "F.Cu" "F.Mask" "F.Paste")
			(net "PVCCIN_CPU1")
		)
		(pad "BE76" smd circle
			(at 28.665424 -5.109972)
			(size 0.4318 0.4318)
			(layers "F.Cu" "F.Mask" "F.Paste")
			(net "PVCCIN_CPU1")
		)
		(pad "BE78" smd circle
			(at 30.382464 -5.109972)
			(size 0.4318 0.4318)
			(layers "F.Cu" "F.Mask" "F.Paste")
			(net "PVCCIN_CPU1")
		)
		(pad "BE80" smd circle
			(at 32.099504 -5.109972)
			(size 0.4318 0.4318)
			(layers "F.Cu" "F.Mask" "F.Paste")
			(net "PVCCIN_CPU1")
		)
		(pad "BE82" smd circle
			(at 33.816544 -5.109972)
			(size 0.4318 0.4318)
			(layers "F.Cu" "F.Mask" "F.Paste")
			(net "PVCCIN_CPU1")
		)
		(pad "BE84" smd circle
			(at 35.533584 -5.109972)
			(size 0.4318 0.4318)
			(layers "F.Cu" "F.Mask" "F.Paste")
			(net "PVCCIN_CPU1")
		)
		(pad "BF3" smd custom
			(at -35.533584 -2.814828 90)
			(size 0.10795 0.10795)
			(layers "F.Cu" "F.Mask" "F.Paste")
			(net "UPI_CPU1_CPU0_P0P0_DN<18>")
			(options
				(clearance outline)
				(anchor circle)
			)
			(primitives
				(gr_poly
					(pts
						(arc
							(start 0.2159 -0.0381)
							(mid 0 -0.254)
							(end -0.2159 -0.0381)
						)
						(arc
							(start -0.2159 0.0381)
							(mid 0 0.254)
							(end 0.2159 0.0381)
						)
					)
					(width 0)
					(fill yes)
				)
			)
		)
		(pad "BF5" smd circle
			(at -33.816544 -2.814828)
			(size 0.4318 0.4318)
			(layers "F.Cu" "F.Mask" "F.Paste")
			(net "VSENSE_PVCCIO_CPU1_SKT_VRTN")
		)
		(pad "BF7" smd circle
			(at -32.099504 -2.814828)
			(size 0.4318 0.4318)
			(layers "F.Cu" "F.Mask" "F.Paste")
			(net "UPI_CPU0_CPU1_P0P0_DP<15>")
		)
		(pad "BF9" smd circle
			(at -30.382464 -2.814828)
			(size 0.4318 0.4318)
			(layers "F.Cu" "F.Mask" "F.Paste")
			(net "GND")
		)
		(pad "BF11" smd circle
			(at -28.665424 -2.814828)
			(size 0.4318 0.4318)
			(layers "F.Cu" "F.Mask" "F.Paste")
			(net "PVCCMCP_CPU1")
		)
		(pad "BF13" smd circle
			(at -26.948384 -2.814828)
			(size 0.4318 0.4318)
			(layers "F.Cu" "F.Mask" "F.Paste")
			(net "PVCCMCP_CPU1")
		)
		(pad "BF15" smd circle
			(at -25.231598 -2.814828)
			(size 0.4318 0.4318)
			(layers "F.Cu" "F.Mask" "F.Paste")
			(net "GND")
		)
		(pad "BF17" smd circle
			(at -23.514558 -2.814828)
			(size 0.4318 0.4318)
			(layers "F.Cu" "F.Mask" "F.Paste")
			(net "GND")
		)
		(pad "BF19" smd circle
			(at -21.797518 -2.814828)
			(size 0.4318 0.4318)
			(layers "F.Cu" "F.Mask" "F.Paste")
			(net "GND")
		)
		(pad "BF21" smd circle
			(at -20.080478 -2.814828)
			(size 0.4318 0.4318)
			(layers "F.Cu" "F.Mask" "F.Paste")
			(net "TP_CPU1_RSVD_146")
		)
		(pad "BF23" smd circle
			(at -18.363438 -2.814828)
			(size 0.4318 0.4318)
			(layers "F.Cu" "F.Mask" "F.Paste")
			(net "PVCCIO_CPU1")
		)
		(pad "BF25" smd circle
			(at -16.646398 -2.814828)
			(size 0.4318 0.4318)
			(layers "F.Cu" "F.Mask" "F.Paste")
			(net "GND")
		)
		(pad "BF27" smd circle
			(at -14.929612 -2.814828)
			(size 0.4318 0.4318)
			(layers "F.Cu" "F.Mask" "F.Paste")
			(net "PVCCIO_CPU1")
		)
		(pad "BF61" smd circle
			(at 15.787878 -4.614926)
			(size 0.4318 0.4318)
			(layers "F.Cu" "F.Mask" "F.Paste")
			(net "PVCCIN_CPU1")
		)
		(pad "BF63" smd circle
			(at 17.504918 -4.614926)
			(size 0.4318 0.4318)
			(layers "F.Cu" "F.Mask" "F.Paste")
			(net "GND")
		)
		(pad "BF65" smd circle
			(at 19.221958 -4.614926)
			(size 0.4318 0.4318)
			(layers "F.Cu" "F.Mask" "F.Paste")
			(net "GND")
		)
		(pad "BF67" smd circle
			(at 20.938998 -4.614926)
			(size 0.4318 0.4318)
			(layers "F.Cu" "F.Mask" "F.Paste")
			(net "GND")
		)
		(pad "BF69" smd circle
			(at 22.656038 -4.614926)
			(size 0.4318 0.4318)
			(layers "F.Cu" "F.Mask" "F.Paste")
			(net "GND")
		)
		(pad "BF71" smd circle
			(at 24.373078 -4.614926)
			(size 0.4318 0.4318)
			(layers "F.Cu" "F.Mask" "F.Paste")
			(net "GND")
		)
		(pad "BF73" smd circle
			(at 26.090118 -4.614926)
			(size 0.4318 0.4318)
			(layers "F.Cu" "F.Mask" "F.Paste")
			(net "PVCCIN_CPU1")
		)
		(pad "BF75" smd circle
			(at 27.806904 -4.614926)
			(size 0.4318 0.4318)
			(layers "F.Cu" "F.Mask" "F.Paste")
			(net "PVCCIN_CPU1")
		)
		(pad "BF77" smd circle
			(at 29.523944 -4.614926)
			(size 0.4318 0.4318)
			(layers "F.Cu" "F.Mask" "F.Paste")
			(net "PVCCIN_CPU1")
		)
		(pad "BF79" smd circle
			(at 31.240984 -4.614926)
			(size 0.4318 0.4318)
			(layers "F.Cu" "F.Mask" "F.Paste")
			(net "PVCCIN_CPU1")
		)
		(pad "BF81" smd circle
			(at 32.958024 -4.614926)
			(size 0.4318 0.4318)
			(layers "F.Cu" "F.Mask" "F.Paste")
			(net "PVCCIN_CPU1")
		)
	)
)
